(kicad_pcb
	(version 20260206)
	(generator "pcbnew")
	(generator_version "10.0")
	(general
		(thickness 1.6)
		(legacy_teardrops no)
	)
	(paper "A4")
	(title_block
		(title "panther-plus-userver — 13130-1b_20150205.brd")
		(comment 1 "Honey Badger (Wiwynn) / footprints 589-597 of 1509")
	)
	(layers
		(0 "F.Cu" signal "TOP")
		(4 "In1.Cu" signal "L2")
		(6 "In2.Cu" signal "L3")
		(8 "In3.Cu" signal "L4")
		(10 "In4.Cu" signal "L5")
		(12 "In5.Cu" signal "L6")
		(14 "In6.Cu" signal "L7")
		(16 "In7.Cu" signal "L8")
		(18 "In8.Cu" signal "L9")
		(20 "In9.Cu" signal "L10")
		(22 "In10.Cu" signal "L11")
		(2 "B.Cu" signal "BOTTOM")
		(9 "F.Adhes" user "F.Adhesive")
		(11 "B.Adhes" user "B.Adhesive")
		(13 "F.Paste" user "Package Geometry/Pastemask Top")
		(15 "B.Paste" user "Package Geometry/Pastemask Bottom")
		(5 "F.SilkS" user "Ref Des/Silkscreen Top")
		(7 "B.SilkS" user "Ref Des/Silkscreen Bottom")
		(1 "F.Mask" user "Board Geometry/Soldermask Top")
		(3 "B.Mask" user "Board Geometry/Soldermask Bottom")
		(17 "Dwgs.User" user "User.Drawings")
		(19 "Cmts.User" user "User.Comments")
		(21 "Eco1.User" user "User.Eco1")
		(23 "Eco2.User" user "User.Eco2")
		(25 "Edge.Cuts" user "Board Geometry/Outline")
		(27 "Margin" user)
		(31 "F.CrtYd" user "Package Geometry/Place Bound Top")
		(29 "B.CrtYd" user "Package Geometry/Place Bound Bottom")
		(35 "F.Fab" user "Ref Des/Assembly Top")
		(33 "B.Fab" user "Ref Des/Assembly Bottom")
	)
	(footprint ""
		(layer "F.Cu")
		(at 31.877 -37.465 90)
		(property "Reference" "R267"
			(at 0 0 90)
			(layer "F.SilkS")
			(hide yes)
			(effects
				(font
					(size 1.27 1.27)
				)
			)
		)
		(property "Value" "51R2F-2-GP"
			(at 0.064008 -3.993896 90)
			(unlocked yes)
			(layer "F.Fab")
			(hide yes)
			(effects
				(font
					(size 1.016 1.016)
					(thickness 0.1524)
				)
			)
		)
		(property "Device Type" "R402H16"
			(at 0.064008 -5.517896 90)
			(unlocked yes)
			(layer "F.Fab")
			(hide yes)
			(effects
				(font
					(size 1.016 1.016)
					(thickness 0.1524)
				)
			)
		)
		(duplicate_pad_numbers_are_jumpers no)
		(fp_rect
			(start -0.381 0.8382)
			(end 0.381 -0.8382)
			(stroke
				(width 0)
				(type default)
			)
			(fill no)
			(layer "F.CrtYd")
		)
		(fp_rect
			(start -0.381 0.8382)
			(end 0.381 -0.8382)
			(stroke
				(width 0)
				(type default)
			)
			(fill no)
			(layer "F.Fab")
		)
		(pad "1" smd custom
			(at 0 -0.4318 90)
			(size 0.127 0.127)
			(layers "F.Cu" "F.Mask" "F.Paste")
			(net "P1V0_STBY")
			(options
				(clearance outline)
				(anchor circle)
			)
			(primitives
				(gr_poly
					(pts
						(arc
							(start -0.2032 -0.2794)
							(mid -0.239121 -0.264521)
							(end -0.254 -0.2286)
						)
						(arc
							(start -0.254 0.2286)
							(mid -0.239121 0.264521)
							(end -0.2032 0.2794)
						)
						(arc
							(start 0.2032 0.2794)
							(mid 0.239121 0.264521)
							(end 0.254 0.2286)
						)
						(arc
							(start 0.254 -0.2286)
							(mid 0.239121 -0.264521)
							(end 0.2032 -0.2794)
						)
					)
					(width 0)
					(fill yes)
				)
			)
		)
		(pad "2" smd custom
			(at 0 0.4318 90)
			(size 0.127 0.127)
			(layers "F.Cu" "F.Mask" "F.Paste")
			(net "XDP_SOC_CPU_TMS")
			(options
				(clearance outline)
				(anchor circle)
			)
			(primitives
				(gr_poly
					(pts
						(arc
							(start -0.2032 -0.2794)
							(mid -0.239121 -0.264521)
							(end -0.254 -0.2286)
						)
						(arc
							(start -0.254 0.2286)
							(mid -0.239121 0.264521)
							(end -0.2032 0.2794)
						)
						(arc
							(start 0.2032 0.2794)
							(mid 0.239121 0.264521)
							(end 0.254 0.2286)
						)
						(arc
							(start 0.254 -0.2286)
							(mid 0.239121 -0.264521)
							(end 0.2032 -0.2794)
						)
					)
					(width 0)
					(fill yes)
				)
			)
		)
	)
	(footprint ""
		(layer "F.Cu")
		(at 66.294 -42.545)
		(property "Reference" "R49"
			(at 0 0 0)
			(layer "F.SilkS")
			(hide yes)
			(effects
				(font
					(size 1.27 1.27)
				)
			)
		)
		(property "Value" "0R2J-2-GP"
			(at 0.064008 -3.993896 0)
			(unlocked yes)
			(layer "F.Fab")
			(hide yes)
			(effects
				(font
					(size 1.016 1.016)
					(thickness 0.1524)
				)
			)
		)
		(property "Device Type" "R402H16"
			(at 0.064008 -5.517896 0)
			(unlocked yes)
			(layer "F.Fab")
			(hide yes)
			(effects
				(font
					(size 1.016 1.016)
					(thickness 0.1524)
				)
			)
		)
		(duplicate_pad_numbers_are_jumpers no)
		(fp_rect
			(start -0.381 0.8382)
			(end 0.381 -0.8382)
			(stroke
				(width 0)
				(type default)
			)
			(fill no)
			(layer "F.CrtYd")
		)
		(fp_rect
			(start -0.381 0.8382)
			(end 0.381 -0.8382)
			(stroke
				(width 0)
				(type default)
			)
			(fill no)
			(layer "F.Fab")
		)
		(pad "1" smd custom
			(at 0 -0.4318)
			(size 0.127 0.127)
			(layers "F.Cu" "F.Mask" "F.Paste")
			(net "SMB_PECI_LV_R_CLK")
			(options
				(clearance outline)
				(anchor circle)
			)
			(primitives
				(gr_poly
					(pts
						(arc
							(start -0.2032 -0.2794)
							(mid -0.239121 -0.264521)
							(end -0.254 -0.2286)
						)
						(arc
							(start -0.254 0.2286)
							(mid -0.239121 0.264521)
							(end -0.2032 0.2794)
						)
						(arc
							(start 0.2032 0.2794)
							(mid 0.239121 0.264521)
							(end 0.254 0.2286)
						)
						(arc
							(start 0.254 -0.2286)
							(mid 0.239121 -0.264521)
							(end 0.2032 -0.2794)
						)
					)
					(width 0)
					(fill yes)
				)
			)
		)
		(pad "2" smd custom
			(at 0 0.4318)
			(size 0.127 0.127)
			(layers "F.Cu" "F.Mask" "F.Paste")
			(net "SMB_PECI_LV_CLK")
			(options
				(clearance outline)
				(anchor circle)
			)
			(primitives
				(gr_poly
					(pts
						(arc
							(start -0.2032 -0.2794)
							(mid -0.239121 -0.264521)
							(end -0.254 -0.2286)
						)
						(arc
							(start -0.254 0.2286)
							(mid -0.239121 0.264521)
							(end -0.2032 0.2794)
						)
						(arc
							(start 0.2032 0.2794)
							(mid 0.239121 0.264521)
							(end 0.254 0.2286)
						)
						(arc
							(start 0.254 -0.2286)
							(mid 0.239121 -0.264521)
							(end 0.2032 -0.2794)
						)
					)
					(width 0)
					(fill yes)
				)
			)
		)
	)
	(footprint ""
		(layer "F.Cu")
		(at 144.907 -48.387 180)
		(property "Reference" "TP43"
			(at 0 0 180)
			(layer "F.SilkS")
			(hide yes)
			(effects
				(font
					(size 1.27 1.27)
				)
			)
		)
		(property "Value" "TPAD32-GP"
			(at 0 -3.166364 180)
			(unlocked yes)
			(layer "F.Fab")
			(hide yes)
			(effects
				(font
					(size 1.016 1.016)
					(thickness 0.1524)
				)
			)
		)
		(property "Device Type" "TPAD32"
			(at 0 -4.690618 180)
			(unlocked yes)
			(layer "F.Fab")
			(hide yes)
			(effects
				(font
					(size 1.016 1.016)
					(thickness 0.1524)
				)
			)
		)
		(duplicate_pad_numbers_are_jumpers no)
		(fp_poly
			(pts
				(arc
					(start -0.7112 0)
					(mid 0.7112 0)
					(end -0.7112 0)
				)
			)
			(stroke
				(width 0)
				(type default)
			)
			(fill no)
			(layer "F.CrtYd")
		)
		(fp_poly
			(pts
				(arc
					(start -0.7112 0)
					(mid 0.7112 0)
					(end -0.7112 0)
				)
			)
			(stroke
				(width 0)
				(type default)
			)
			(fill no)
			(layer "F.Fab")
		)
		(pad "1" smd circle
			(at 0 0 180)
			(size 0.8128 0.8128)
			(layers "F.Cu" "F.Mask" "F.Paste")
			(net "C_DCLK")
		)
	)
	(footprint ""
		(layer "F.Cu")
		(at 157.607 -33.782 -90)
		(property "Reference" "LED4"
			(at 0 0 270)
			(layer "F.SilkS")
			(hide yes)
			(effects
				(font
					(size 1.27 1.27)
				)
			)
		)
		(property "Value" "LED-YG-51-GP"
			(at -2.6924 -1.4224 270)
			(unlocked yes)
			(layer "F.Fab")
			(hide yes)
			(effects
				(font
					(size 1.016 1.016)
					(thickness 0.1524)
				)
			)
		)
		(property "Device Type" "LED1608AKH40"
			(at -2.6924 -2.9464 270)
			(unlocked yes)
			(layer "F.Fab")
			(hide yes)
			(effects
				(font
					(size 1.016 1.016)
					(thickness 0.1524)
				)
			)
		)
		(duplicate_pad_numbers_are_jumpers no)
		(fp_line
			(start -0.5334 1.3081)
			(end 0.5334 1.3081)
			(stroke
				(width 0.254)
				(type default)
			)
			(layer "F.SilkS")
		)
		(fp_rect
			(start -0.6604 1.1811)
			(end 0.6604 -1.1811)
			(stroke
				(width 0)
				(type default)
			)
			(fill no)
			(layer "F.CrtYd")
		)
		(fp_rect
			(start -0.6604 1.1811)
			(end 0.6604 -1.1811)
			(stroke
				(width 0)
				(type default)
			)
			(fill no)
			(layer "F.Fab")
		)
		(pad "A" smd rect
			(at 0 -0.652526 270)
			(size 1.0668 0.8128)
			(layers "F.Cu" "F.Mask" "F.Paste")
			(net "HEARTBEAT_R_LED")
		)
		(pad "K" smd rect
			(at 0 0.652526 270)
			(size 1.0668 0.8128)
			(layers "F.Cu" "F.Mask" "F.Paste")
			(net "HEARTBEAT_LED")
		)
	)
	(footprint ""
		(layer "F.Cu")
		(at 197.231 -39.243 90)
		(property "Reference" "PR97"
			(at 0 0 90)
			(layer "F.SilkS")
			(hide yes)
			(effects
				(font
					(size 1.27 1.27)
				)
			)
		)
		(property "Value" "0R3J-0-U-GP"
			(at -0.0254 -2.0193 90)
			(unlocked yes)
			(layer "F.Fab")
			(hide yes)
			(effects
				(font
					(size 1.016 1.016)
					(thickness 0.1524)
				)
			)
		)
		(property "Device Type" "R603H22"
			(at -0.0254 -3.5433 90)
			(unlocked yes)
			(layer "F.Fab")
			(hide yes)
			(effects
				(font
					(size 1.016 1.016)
					(thickness 0.1524)
				)
			)
		)
		(duplicate_pad_numbers_are_jumpers no)
		(fp_line
			(start 0.4318 0)
			(end 0.2032 0)
			(stroke
				(width 0.2032)
				(type default)
			)
			(layer "F.SilkS")
		)
		(fp_line
			(start -0.2032 0)
			(end -0.4191 0)
			(stroke
				(width 0.2032)
				(type default)
			)
			(layer "F.SilkS")
		)
		(fp_rect
			(start -0.635 1.1811)
			(end 0.635 -1.1811)
			(stroke
				(width 0)
				(type default)
			)
			(fill no)
			(layer "F.CrtYd")
		)
		(fp_rect
			(start -0.635 1.1811)
			(end 0.635 -1.1811)
			(stroke
				(width 0)
				(type default)
			)
			(fill no)
			(layer "F.Fab")
		)
		(pad "1" smd custom
			(at 0 -0.6604 90)
			(size 0.19685 0.19685)
			(layers "F.Cu" "F.Mask" "F.Paste")
			(net "VR_PVDDR_A_GL1")
			(options
				(clearance outline)
				(anchor circle)
			)
			(primitives
				(gr_poly
					(pts
						(arc
							(start 0.508 -0.2921)
							(mid 0.478242 -0.363942)
							(end 0.4064 -0.3937)
						)
						(arc
							(start -0.4064 -0.3937)
							(mid -0.478242 -0.363942)
							(end -0.508 -0.2921)
						)
						(arc
							(start -0.508 0.2921)
							(mid -0.478242 0.363942)
							(end -0.4064 0.3937)
						)
						(arc
							(start 0.4064 0.3937)
							(mid 0.478242 0.363942)
							(end 0.508 0.2921)
						)
					)
					(width 0)
					(fill yes)
				)
			)
		)
		(pad "2" smd custom
			(at 0 0.6604 90)
			(size 0.19685 0.19685)
			(layers "F.Cu" "F.Mask" "F.Paste")
			(net "VR_PVDDR_A_GL1_BG")
			(options
				(clearance outline)
				(anchor circle)
			)
			(primitives
				(gr_poly
					(pts
						(arc
							(start 0.508 -0.2921)
							(mid 0.478242 -0.363942)
							(end 0.4064 -0.3937)
						)
						(arc
							(start -0.4064 -0.3937)
							(mid -0.478242 -0.363942)
							(end -0.508 -0.2921)
						)
						(arc
							(start -0.508 0.2921)
							(mid -0.478242 0.363942)
							(end -0.4064 0.3937)
						)
						(arc
							(start 0.4064 0.3937)
							(mid 0.478242 0.363942)
							(end 0.508 0.2921)
						)
					)
					(width 0)
					(fill yes)
				)
			)
		)
	)
	(footprint ""
		(layer "F.Cu")
		(at 20.5486 -35.3568 -90)
		(property "Reference" "PC152"
			(at 0 0 270)
			(layer "F.SilkS")
			(hide yes)
			(effects
				(font
					(size 1.27 1.27)
				)
			)
		)
		(property "Value" "SCD1U25V2KX-2-GP"
			(at 1.8923 -1.2065 270)
			(unlocked yes)
			(layer "F.Fab")
			(hide yes)
			(effects
				(font
					(size 1.016 1.016)
					(thickness 0.1524)
				)
			)
		)
		(property "Device Type" "C402H22"
			(at 1.8923 -2.7305 270)
			(unlocked yes)
			(layer "F.Fab")
			(hide yes)
			(effects
				(font
					(size 1.016 1.016)
					(thickness 0.1524)
				)
			)
		)
		(duplicate_pad_numbers_are_jumpers no)
		(fp_rect
			(start -0.381 0.7366)
			(end 0.381 -0.7366)
			(stroke
				(width 0)
				(type default)
			)
			(fill no)
			(layer "F.CrtYd")
		)
		(fp_rect
			(start -0.381 0.7366)
			(end 0.381 -0.7366)
			(stroke
				(width 0)
				(type default)
			)
			(fill no)
			(layer "F.Fab")
		)
		(pad "1" smd custom
			(at 0 -0.4572 270)
			(size 0.1143 0.1143)
			(layers "F.Cu" "F.Mask" "F.Paste")
			(net "P3V3_STBY_OUT")
			(options
				(clearance outline)
				(anchor circle)
			)
			(primitives
				(gr_poly
					(pts
						(arc
							(start -0.254 -0.1778)
							(mid -0.239121 -0.213721)
							(end -0.2032 -0.2286)
						)
						(arc
							(start 0.2032 -0.2286)
							(mid 0.239121 -0.213721)
							(end 0.254 -0.1778)
						)
						(arc
							(start 0.254 0.1778)
							(mid 0.239121 0.213721)
							(end 0.2032 0.2286)
						)
						(arc
							(start -0.2032 0.2286)
							(mid -0.239121 0.213721)
							(end -0.254 0.1778)
						)
					)
					(width 0)
					(fill yes)
				)
			)
		)
		(pad "2" smd custom
			(at 0 0.4572 270)
			(size 0.1143 0.1143)
			(layers "F.Cu" "F.Mask" "F.Paste")
			(net "P3V3_STBY_LL_R")
			(options
				(clearance outline)
				(anchor circle)
			)
			(primitives
				(gr_poly
					(pts
						(arc
							(start -0.254 -0.1778)
							(mid -0.239121 -0.213721)
							(end -0.2032 -0.2286)
						)
						(arc
							(start 0.2032 -0.2286)
							(mid 0.239121 -0.213721)
							(end 0.254 -0.1778)
						)
						(arc
							(start 0.254 0.1778)
							(mid 0.239121 0.213721)
							(end 0.2032 0.2286)
						)
						(arc
							(start -0.2032 0.2286)
							(mid -0.239121 0.213721)
							(end -0.254 0.1778)
						)
					)
					(width 0)
					(fill yes)
				)
			)
		)
	)
	(footprint ""
		(layer "F.Cu")
		(at 38.1 -42.037 180)
		(property "Reference" "R63"
			(at 0 0 180)
			(layer "F.SilkS")
			(hide yes)
			(effects
				(font
					(size 1.27 1.27)
				)
			)
		)
		(property "Value" "10KR2F-2-GP"
			(at 1.7907 -1.1176 180)
			(unlocked yes)
			(layer "F.Fab")
			(hide yes)
			(effects
				(font
					(size 1.016 1.016)
					(thickness 0.1524)
				)
			)
		)
		(property "Device Type" "R402H16"
			(at 1.7907 -2.6416 180)
			(unlocked yes)
			(layer "F.Fab")
			(hide yes)
			(effects
				(font
					(size 1.016 1.016)
					(thickness 0.1524)
				)
			)
		)
		(duplicate_pad_numbers_are_jumpers no)
		(fp_rect
			(start -0.381 0.8382)
			(end 0.381 -0.8382)
			(stroke
				(width 0)
				(type default)
			)
			(fill no)
			(layer "F.CrtYd")
		)
		(fp_rect
			(start -0.381 0.8382)
			(end 0.381 -0.8382)
			(stroke
				(width 0)
				(type default)
			)
			(fill no)
			(layer "F.Fab")
		)
		(pad "1" smd custom
			(at 0 -0.4318 180)
			(size 0.127 0.127)
			(layers "F.Cu" "F.Mask" "F.Paste")
			(net "CPU_RSMRST#")
			(options
				(clearance outline)
				(anchor circle)
			)
			(primitives
				(gr_poly
					(pts
						(arc
							(start -0.2032 -0.2794)
							(mid -0.239121 -0.264521)
							(end -0.254 -0.2286)
						)
						(arc
							(start -0.254 0.2286)
							(mid -0.239121 0.264521)
							(end -0.2032 0.2794)
						)
						(arc
							(start 0.2032 0.2794)
							(mid 0.239121 0.264521)
							(end 0.254 0.2286)
						)
						(arc
							(start 0.254 -0.2286)
							(mid 0.239121 -0.264521)
							(end 0.2032 -0.2794)
						)
					)
					(width 0)
					(fill yes)
				)
			)
		)
		(pad "2" smd custom
			(at 0 0.4318 180)
			(size 0.127 0.127)
			(layers "F.Cu" "F.Mask" "F.Paste")
			(net "GND")
			(options
				(clearance outline)
				(anchor circle)
			)
			(primitives
				(gr_poly
					(pts
						(arc
							(start -0.2032 -0.2794)
							(mid -0.239121 -0.264521)
							(end -0.254 -0.2286)
						)
						(arc
							(start -0.254 0.2286)
							(mid -0.239121 0.264521)
							(end -0.2032 0.2794)
						)
						(arc
							(start 0.2032 0.2794)
							(mid 0.239121 0.264521)
							(end 0.254 0.2286)
						)
						(arc
							(start 0.254 -0.2286)
							(mid 0.239121 -0.264521)
							(end 0.2032 -0.2794)
						)
					)
					(width 0)
					(fill yes)
				)
			)
		)
	)
	(footprint ""
		(layer "F.Cu")
		(at 172.212 -39.751 90)
		(property "Reference" "PC212"
			(at 0 0 90)
			(layer "F.SilkS")
			(hide yes)
			(effects
				(font
					(size 1.27 1.27)
				)
			)
		)
		(property "Value" "SC4D7U10V3KX-GP"
			(at -0.0254 -2.0193 90)
			(unlocked yes)
			(layer "F.Fab")
			(hide yes)
			(effects
				(font
					(size 1.016 1.016)
					(thickness 0.1524)
				)
			)
		)
		(property "Device Type" "C603H36"
			(at -0.0254 -3.5433 90)
			(unlocked yes)
			(layer "F.Fab")
			(hide yes)
			(effects
				(font
					(size 1.016 1.016)
					(thickness 0.1524)
				)
			)
		)
		(duplicate_pad_numbers_are_jumpers no)
		(fp_line
			(start -0.4064 0)
			(end 0.4064 0)
			(stroke
				(width 0.2286)
				(type default)
			)
			(layer "F.SilkS")
		)
		(fp_rect
			(start -0.635 1.1811)
			(end 0.635 -1.1811)
			(stroke
				(width 0)
				(type default)
			)
			(fill no)
			(layer "F.CrtYd")
		)
		(fp_rect
			(start -0.635 1.1811)
			(end 0.635 -1.1811)
			(stroke
				(width 0)
				(type default)
			)
			(fill no)
			(layer "F.Fab")
		)
		(pad "1" smd custom
			(at 0 -0.6604 90)
			(size 0.19685 0.19685)
			(layers "F.Cu" "F.Mask" "F.Paste")
			(net "P2V5_STBY_OUT")
			(options
				(clearance outline)
				(anchor circle)
			)
			(primitives
				(gr_poly
					(pts
						(arc
							(start 0.508 -0.2921)
							(mid 0.478242 -0.363942)
							(end 0.4064 -0.3937)
						)
						(arc
							(start -0.4064 -0.3937)
							(mid -0.478242 -0.363942)
							(end -0.508 -0.2921)
						)
						(arc
							(start -0.508 0.2921)
							(mid -0.478242 0.363942)
							(end -0.4064 0.3937)
						)
						(arc
							(start 0.4064 0.3937)
							(mid 0.478242 0.363942)
							(end 0.508 0.2921)
						)
					)
					(width 0)
					(fill yes)
				)
			)
		)
		(pad "2" smd custom
			(at 0 0.6604 90)
			(size 0.19685 0.19685)
			(layers "F.Cu" "F.Mask" "F.Paste")
			(net "GND")
			(options
				(clearance outline)
				(anchor circle)
			)
			(primitives
				(gr_poly
					(pts
						(arc
							(start 0.508 -0.2921)
							(mid 0.478242 -0.363942)
							(end 0.4064 -0.3937)
						)
						(arc
							(start -0.4064 -0.3937)
							(mid -0.478242 -0.363942)
							(end -0.508 -0.2921)
						)
						(arc
							(start -0.508 0.2921)
							(mid -0.478242 0.363942)
							(end -0.4064 0.3937)
						)
						(arc
							(start 0.4064 0.3937)
							(mid 0.478242 0.363942)
							(end 0.508 0.2921)
						)
					)
					(width 0)
					(fill yes)
				)
			)
		)
	)
	(footprint ""
		(layer "F.Cu")
		(at 37.592 -39.116)
		(property "Reference" "R242"
			(at 0 0 0)
			(layer "F.SilkS")
			(hide yes)
			(effects
				(font
					(size 1.27 1.27)
				)
			)
		)
		(property "Value" "0R2J-2-GP"
			(at 0.064008 -3.993896 0)
			(unlocked yes)
			(layer "F.Fab")
			(hide yes)
			(effects
				(font
					(size 1.016 1.016)
					(thickness 0.1524)
				)
			)
		)
		(property "Device Type" "R402H16"
			(at 0.064008 -5.517896 0)
			(unlocked yes)
			(layer "F.Fab")
			(hide yes)
			(effects
				(font
					(size 1.016 1.016)
					(thickness 0.1524)
				)
			)
		)
		(duplicate_pad_numbers_are_jumpers no)
		(fp_rect
			(start -0.381 0.8382)
			(end 0.381 -0.8382)
			(stroke
				(width 0)
				(type default)
			)
			(fill no)
			(layer "F.CrtYd")
		)
		(fp_rect
			(start -0.381 0.8382)
			(end 0.381 -0.8382)
			(stroke
				(width 0)
				(type default)
			)
			(fill no)
			(layer "F.Fab")
		)
		(pad "1" smd custom
			(at 0 -0.4318)
			(size 0.127 0.127)
			(layers "F.Cu" "F.Mask" "F.Paste")
			(net "SMBUS_HOST_DATA")
			(options
				(clearance outline)
				(anchor circle)
			)
			(primitives
				(gr_poly
					(pts
						(arc
							(start -0.2032 -0.2794)
							(mid -0.239121 -0.264521)
							(end -0.254 -0.2286)
						)
						(arc
							(start -0.254 0.2286)
							(mid -0.239121 0.264521)
							(end -0.2032 0.2794)
						)
						(arc
							(start 0.2032 0.2794)
							(mid 0.239121 0.264521)
							(end 0.254 0.2286)
						)
						(arc
							(start 0.254 -0.2286)
							(mid 0.239121 -0.264521)
							(end 0.2032 -0.2794)
						)
					)
					(width 0)
					(fill yes)
				)
			)
		)
		(pad "2" smd custom
			(at 0 0.4318)
			(size 0.127 0.127)
			(layers "F.Cu" "F.Mask" "F.Paste")
			(net "SMB_XDP_DATA_R")
			(options
				(clearance outline)
				(anchor circle)
			)
			(primitives
				(gr_poly
					(pts
						(arc
							(start -0.2032 -0.2794)
							(mid -0.239121 -0.264521)
							(end -0.254 -0.2286)
						)
						(arc
							(start -0.254 0.2286)
							(mid -0.239121 0.264521)
							(end -0.2032 0.2794)
						)
						(arc
							(start 0.2032 0.2794)
							(mid 0.239121 0.264521)
							(end 0.254 0.2286)
						)
						(arc
							(start 0.254 -0.2286)
							(mid 0.239121 -0.264521)
							(end 0.2032 -0.2794)
						)
					)
					(width 0)
					(fill yes)
				)
			)
		)
	)
)
